(kicad_pcb
	(version 20260206)
	(generator "pcbnew")
	(generator_version "10.0")
	(general
		(thickness 1.6)
		(legacy_teardrops no)
	)
	(paper "A4")
	(title_block
		(title "03242023_DA0F0TMBIJ0_F0T_Motherboard_J_brd_V01_OCP.brd")
		(comment 1 "Grand Teton / footprints 4956-4962 of 6105")
	)
	(layers
		(0 "F.Cu" signal "TOP")
		(4 "In1.Cu" signal "GND")
		(6 "In2.Cu" signal "IN1")
		(8 "In3.Cu" signal "GND1")
		(10 "In4.Cu" signal "IN2")
		(12 "In5.Cu" signal "GND2")
		(14 "In6.Cu" signal "IN3")
		(16 "In7.Cu" signal "GND3")
		(18 "In8.Cu" signal "VCC")
		(20 "In9.Cu" signal "VCC1")
		(22 "In10.Cu" signal "GND4")
		(24 "In11.Cu" signal "IN4")
		(26 "In12.Cu" signal "GND5")
		(28 "In13.Cu" signal "IN5")
		(30 "In14.Cu" signal "GND6")
		(32 "In15.Cu" signal "IN6")
		(34 "In16.Cu" signal "GND7")
		(2 "B.Cu" signal "BOTTOM")
		(9 "F.Adhes" user "F.Adhesive")
		(11 "B.Adhes" user "B.Adhesive")
		(13 "F.Paste" user "Package Geometry/Pastemask Top")
		(15 "B.Paste" user "Package Geometry/Pastemask Bottom")
		(5 "F.SilkS" user "Ref Des/Silkscreen Top")
		(7 "B.SilkS" user "Ref Des/Silkscreen Bottom")
		(1 "F.Mask" user "Board Geometry/Soldermask Top")
		(3 "B.Mask" user "Board Geometry/Soldermask Bottom")
		(17 "Dwgs.User" user "User.Drawings")
		(19 "Cmts.User" user "User.Comments")
		(21 "Eco1.User" user "User.Eco1")
		(23 "Eco2.User" user "User.Eco2")
		(25 "Edge.Cuts" user "Board Geometry/Outline")
		(27 "Margin" user)
		(31 "F.CrtYd" user "Package Geometry/Place Bound Top")
		(29 "B.CrtYd" user "Package Geometry/Place Bound Bottom")
		(35 "F.Fab" user "Ref Des/Assembly Top")
		(33 "B.Fab" user "Ref Des/Assembly Bottom")
	)
	(footprint ""
		(layer "B.Cu")
		(at 75.06208 -4.251198 -90)
		(property "Reference" "R3166"
			(at 0 0 90)
			(layer "B.SilkS")
			(hide yes)
			(effects
				(font
					(size 1.27 1.27)
				)
				(justify mirror)
			)
		)
		(property "Value" ""
			(at 0 0 90)
			(layer "B.Fab")
			(effects
				(font
					(size 1.27 1.27)
				)
				(justify mirror)
			)
		)
		(duplicate_pad_numbers_are_jumpers no)
		(fp_line
			(start -0.7874 0.4064)
			(end 0.7874 0.4064)
			(stroke
				(width 0.1524)
				(type default)
			)
			(layer "B.SilkS")
		)
		(fp_line
			(start 0.7874 0.4064)
			(end 0.7874 -0.4064)
			(stroke
				(width 0.1524)
				(type default)
			)
			(layer "B.SilkS")
		)
		(fp_line
			(start -0.7874 -0.4064)
			(end -0.7874 0.4064)
			(stroke
				(width 0.1524)
				(type default)
			)
			(layer "B.SilkS")
		)
		(fp_line
			(start 0.7874 -0.4064)
			(end -0.7874 -0.4064)
			(stroke
				(width 0.1524)
				(type default)
			)
			(layer "B.SilkS")
		)
		(fp_line
			(start -0.67945 0.3048)
			(end -0.120396 0.3048)
			(stroke
				(width 0.1)
				(type default)
			)
			(layer "B.Fab")
		)
		(fp_line
			(start -0.120396 0.3048)
			(end -0.120396 0.2794)
			(stroke
				(width 0.1)
				(type default)
			)
			(layer "B.Fab")
		)
		(fp_line
			(start 0.12065 0.3048)
			(end 0.67945 0.3048)
			(stroke
				(width 0.1)
				(type default)
			)
			(layer "B.Fab")
		)
		(fp_line
			(start 0.67945 0.3048)
			(end 0.67945 -0.305054)
			(stroke
				(width 0.1)
				(type default)
			)
			(layer "B.Fab")
		)
		(fp_line
			(start -0.120396 0.2794)
			(end 0.12065 0.2794)
			(stroke
				(width 0.1)
				(type default)
			)
			(layer "B.Fab")
		)
		(fp_line
			(start 0.12065 0.2794)
			(end 0.12065 0.3048)
			(stroke
				(width 0.1)
				(type default)
			)
			(layer "B.Fab")
		)
		(fp_line
			(start -0.12065 -0.2794)
			(end -0.12065 -0.3048)
			(stroke
				(width 0.1)
				(type default)
			)
			(layer "B.Fab")
		)
		(fp_line
			(start 0.12065 -0.2794)
			(end -0.12065 -0.2794)
			(stroke
				(width 0.1)
				(type default)
			)
			(layer "B.Fab")
		)
		(fp_line
			(start -0.67945 -0.3048)
			(end -0.67945 0.3048)
			(stroke
				(width 0.1)
				(type default)
			)
			(layer "B.Fab")
		)
		(fp_line
			(start -0.12065 -0.3048)
			(end -0.67945 -0.3048)
			(stroke
				(width 0.1)
				(type default)
			)
			(layer "B.Fab")
		)
		(fp_line
			(start 0.12065 -0.305054)
			(end 0.12065 -0.2794)
			(stroke
				(width 0.1)
				(type default)
			)
			(layer "B.Fab")
		)
		(fp_line
			(start 0.67945 -0.305054)
			(end 0.12065 -0.305054)
			(stroke
				(width 0.1)
				(type default)
			)
			(layer "B.Fab")
		)
		(pad "1" smd circle
			(at 0.40005 0 90)
			(size 0 0)
			(layers "B.Cu" "B.Mask" "B.Paste")
			(net "P3V3_OCP_V3_2")
		)
		(pad "2" smd circle
			(at -0.40005 0 90)
			(size 0 0)
			(layers "B.Cu" "B.Mask" "B.Paste")
			(net "OCP_V3_2_ID1")
		)
	)
	(footprint ""
		(layer "B.Cu")
		(at 36.488624 -405.93137 180)
		(property "Reference" "R5234"
			(at 0 0 0)
			(layer "B.SilkS")
			(hide yes)
			(effects
				(font
					(size 1.27 1.27)
				)
				(justify mirror)
			)
		)
		(property "Value" ""
			(at 0 0 0)
			(layer "B.Fab")
			(effects
				(font
					(size 1.27 1.27)
				)
				(justify mirror)
			)
		)
		(duplicate_pad_numbers_are_jumpers no)
		(fp_line
			(start 0.7874 -0.076962)
			(end 0.7874 -0.4064)
			(stroke
				(width 0.1524)
				(type default)
			)
			(layer "B.SilkS")
		)
		(fp_line
			(start 0.7874 -0.4064)
			(end -0.7874 -0.4064)
			(stroke
				(width 0.1524)
				(type default)
			)
			(layer "B.SilkS")
		)
		(fp_line
			(start -0.407416 0.4064)
			(end 0.529844 0.4064)
			(stroke
				(width 0.1524)
				(type default)
			)
			(layer "B.SilkS")
		)
		(fp_line
			(start -0.7874 -0.4064)
			(end -0.7874 0.027178)
			(stroke
				(width 0.1524)
				(type default)
			)
			(layer "B.SilkS")
		)
		(fp_line
			(start 0.67945 0.3048)
			(end 0.67945 -0.305054)
			(stroke
				(width 0.1)
				(type default)
			)
			(layer "B.Fab")
		)
		(fp_line
			(start 0.67945 -0.305054)
			(end 0.12065 -0.305054)
			(stroke
				(width 0.1)
				(type default)
			)
			(layer "B.Fab")
		)
		(fp_line
			(start 0.12065 0.3048)
			(end 0.67945 0.3048)
			(stroke
				(width 0.1)
				(type default)
			)
			(layer "B.Fab")
		)
		(fp_line
			(start 0.12065 0.2794)
			(end 0.12065 0.3048)
			(stroke
				(width 0.1)
				(type default)
			)
			(layer "B.Fab")
		)
		(fp_line
			(start 0.12065 -0.2794)
			(end -0.12065 -0.2794)
			(stroke
				(width 0.1)
				(type default)
			)
			(layer "B.Fab")
		)
		(fp_line
			(start 0.12065 -0.305054)
			(end 0.12065 -0.2794)
			(stroke
				(width 0.1)
				(type default)
			)
			(layer "B.Fab")
		)
		(fp_line
			(start -0.120396 0.3048)
			(end -0.120396 0.2794)
			(stroke
				(width 0.1)
				(type default)
			)
			(layer "B.Fab")
		)
		(fp_line
			(start -0.120396 0.2794)
			(end 0.12065 0.2794)
			(stroke
				(width 0.1)
				(type default)
			)
			(layer "B.Fab")
		)
		(fp_line
			(start -0.12065 -0.2794)
			(end -0.12065 -0.3048)
			(stroke
				(width 0.1)
				(type default)
			)
			(layer "B.Fab")
		)
		(fp_line
			(start -0.12065 -0.3048)
			(end -0.67945 -0.3048)
			(stroke
				(width 0.1)
				(type default)
			)
			(layer "B.Fab")
		)
		(fp_line
			(start -0.67945 0.3048)
			(end -0.120396 0.3048)
			(stroke
				(width 0.1)
				(type default)
			)
			(layer "B.Fab")
		)
		(fp_line
			(start -0.67945 -0.3048)
			(end -0.67945 0.3048)
			(stroke
				(width 0.1)
				(type default)
			)
			(layer "B.Fab")
		)
		(pad "1" smd circle
			(at 0.40005 0)
			(size 0 0)
			(layers "B.Cu" "B.Mask" "B.Paste")
			(net "USB2_HUB_BUF_SWB_R_DP")
		)
		(pad "2" smd circle
			(at -0.40005 0)
			(size 0 0)
			(layers "B.Cu" "B.Mask" "B.Paste")
			(net "USB2_HUB_BUF_SWB_DP")
		)
	)
	(footprint ""
		(layer "B.Cu")
		(at 180.155596 -112.97539 180)
		(property "Reference" "C1912"
			(at 0 0 0)
			(layer "B.SilkS")
			(hide yes)
			(effects
				(font
					(size 1.27 1.27)
				)
				(justify mirror)
			)
		)
		(property "Value" ""
			(at 0 0 0)
			(layer "B.Fab")
			(effects
				(font
					(size 1.27 1.27)
				)
				(justify mirror)
			)
		)
		(duplicate_pad_numbers_are_jumpers no)
		(fp_line
			(start 0.69215 0.2921)
			(end 0.69215 -0.2921)
			(stroke
				(width 0.1524)
				(type default)
			)
			(layer "B.SilkS")
		)
		(fp_line
			(start 0.69215 -0.2921)
			(end -0.69215 -0.2921)
			(stroke
				(width 0.1524)
				(type default)
			)
			(layer "B.SilkS")
		)
		(fp_line
			(start -0.69215 0.2921)
			(end 0.69215 0.2921)
			(stroke
				(width 0.1524)
				(type default)
			)
			(layer "B.SilkS")
		)
		(fp_line
			(start -0.69215 -0.2921)
			(end -0.69215 0.2921)
			(stroke
				(width 0.1524)
				(type default)
			)
			(layer "B.SilkS")
		)
		(fp_line
			(start 0.51435 0.2794)
			(end 0.51435 -0.2794)
			(stroke
				(width 0.1)
				(type default)
			)
			(layer "B.Fab")
		)
		(fp_line
			(start 0.51435 -0.2794)
			(end -0.51435 -0.2794)
			(stroke
				(width 0.1)
				(type default)
			)
			(layer "B.Fab")
		)
		(fp_line
			(start -0.51435 0.2794)
			(end 0.51435 0.2794)
			(stroke
				(width 0.1)
				(type default)
			)
			(layer "B.Fab")
		)
		(fp_line
			(start -0.51435 -0.2794)
			(end -0.51435 0.2794)
			(stroke
				(width 0.1)
				(type default)
			)
			(layer "B.Fab")
		)
		(pad "1" smd circle
			(at 0.40005 0)
			(size 0 0)
			(layers "B.Cu" "B.Mask" "B.Paste")
			(net "VCC_PLD_CORE")
		)
		(pad "2" smd circle
			(at -0.40005 0)
			(size 0 0)
			(layers "B.Cu" "B.Mask" "B.Paste")
			(net "GND")
		)
		(zone
			(layer "B.Cu")
			(hatch none 0.5)
			(connect_pads
				(clearance 0)
			)
			(min_thickness 0.25)
			(keepout
				(tracks not_allowed)
				(vias allowed)
				(pads allowed)
				(copperpour not_allowed)
				(footprints allowed)
			)
			(placement
				(enabled no)
				(sheetname "")
			)
			(fill
				(thermal_gap 0.5)
				(thermal_bridge_width 0.5)
				(island_removal_mode 0)
			)
			(polygon
				(pts
					(xy 179.965096 -113.06302) (xy 180.056536 -113.121186) (xy 180.255926 -113.121186) (xy 180.346096 -113.06302)
					(xy 180.346096 -112.88776) (xy 180.255926 -112.82934) (xy 180.056536 -112.82934) (xy 179.965096 -112.887506)
				)
			)
		)
	)
	(footprint ""
		(layer "B.Cu")
		(at 418.540692 -174.686468 180)
		(property "Reference" "PR1776"
			(at 0 0 0)
			(layer "B.SilkS")
			(hide yes)
			(effects
				(font
					(size 1.27 1.27)
				)
				(justify mirror)
			)
		)
		(property "Value" ""
			(at 0 0 0)
			(layer "B.Fab")
			(effects
				(font
					(size 1.27 1.27)
				)
				(justify mirror)
			)
		)
		(duplicate_pad_numbers_are_jumpers no)
		(fp_line
			(start 0.7874 0.4064)
			(end 0.7874 -0.4064)
			(stroke
				(width 0.1524)
				(type default)
			)
			(layer "B.SilkS")
		)
		(fp_line
			(start 0.7874 -0.4064)
			(end -0.7874 -0.4064)
			(stroke
				(width 0.1524)
				(type default)
			)
			(layer "B.SilkS")
		)
		(fp_line
			(start -0.7874 0.4064)
			(end 0.7874 0.4064)
			(stroke
				(width 0.1524)
				(type default)
			)
			(layer "B.SilkS")
		)
		(fp_line
			(start -0.7874 -0.4064)
			(end -0.7874 0.4064)
			(stroke
				(width 0.1524)
				(type default)
			)
			(layer "B.SilkS")
		)
		(fp_line
			(start 0.67945 0.3048)
			(end 0.67945 -0.305054)
			(stroke
				(width 0.1)
				(type default)
			)
			(layer "B.Fab")
		)
		(fp_line
			(start 0.67945 -0.305054)
			(end 0.12065 -0.305054)
			(stroke
				(width 0.1)
				(type default)
			)
			(layer "B.Fab")
		)
		(fp_line
			(start 0.12065 0.3048)
			(end 0.67945 0.3048)
			(stroke
				(width 0.1)
				(type default)
			)
			(layer "B.Fab")
		)
		(fp_line
			(start 0.12065 0.2794)
			(end 0.12065 0.3048)
			(stroke
				(width 0.1)
				(type default)
			)
			(layer "B.Fab")
		)
		(fp_line
			(start 0.12065 -0.2794)
			(end -0.12065 -0.2794)
			(stroke
				(width 0.1)
				(type default)
			)
			(layer "B.Fab")
		)
		(fp_line
			(start 0.12065 -0.305054)
			(end 0.12065 -0.2794)
			(stroke
				(width 0.1)
				(type default)
			)
			(layer "B.Fab")
		)
		(fp_line
			(start -0.120396 0.3048)
			(end -0.120396 0.2794)
			(stroke
				(width 0.1)
				(type default)
			)
			(layer "B.Fab")
		)
		(fp_line
			(start -0.120396 0.2794)
			(end 0.12065 0.2794)
			(stroke
				(width 0.1)
				(type default)
			)
			(layer "B.Fab")
		)
		(fp_line
			(start -0.12065 -0.2794)
			(end -0.12065 -0.3048)
			(stroke
				(width 0.1)
				(type default)
			)
			(layer "B.Fab")
		)
		(fp_line
			(start -0.12065 -0.3048)
			(end -0.67945 -0.3048)
			(stroke
				(width 0.1)
				(type default)
			)
			(layer "B.Fab")
		)
		(fp_line
			(start -0.67945 0.3048)
			(end -0.120396 0.3048)
			(stroke
				(width 0.1)
				(type default)
			)
			(layer "B.Fab")
		)
		(fp_line
			(start -0.67945 -0.3048)
			(end -0.67945 0.3048)
			(stroke
				(width 0.1)
				(type default)
			)
			(layer "B.Fab")
		)
		(pad "1" smd circle
			(at 0.40005 0)
			(size 0 0)
			(layers "B.Cu" "B.Mask" "B.Paste")
			(net "PVCCINFAON_CPU0_VOS1")
		)
		(pad "2" smd circle
			(at -0.40005 0)
			(size 0 0)
			(layers "B.Cu" "B.Mask" "B.Paste")
			(net "PVCCINFAON_CPU0")
		)
	)
	(footprint ""
		(layer "B.Cu")
		(at 372.299738 -359.50271 -90)
		(property "Reference" "PR3335"
			(at 0 0 90)
			(layer "B.SilkS")
			(hide yes)
			(effects
				(font
					(size 1.27 1.27)
				)
				(justify mirror)
			)
		)
		(property "Value" ""
			(at 0 0 90)
			(layer "B.Fab")
			(effects
				(font
					(size 1.27 1.27)
				)
				(justify mirror)
			)
		)
		(duplicate_pad_numbers_are_jumpers no)
		(fp_line
			(start -0.7874 0.4064)
			(end 0.7874 0.4064)
			(stroke
				(width 0.1524)
				(type default)
			)
			(layer "B.SilkS")
		)
		(fp_line
			(start 0.7874 0.4064)
			(end 0.7874 -0.4064)
			(stroke
				(width 0.1524)
				(type default)
			)
			(layer "B.SilkS")
		)
		(fp_line
			(start -0.7874 -0.4064)
			(end -0.7874 0.4064)
			(stroke
				(width 0.1524)
				(type default)
			)
			(layer "B.SilkS")
		)
		(fp_line
			(start 0.7874 -0.4064)
			(end -0.7874 -0.4064)
			(stroke
				(width 0.1524)
				(type default)
			)
			(layer "B.SilkS")
		)
		(fp_line
			(start -0.67945 0.3048)
			(end -0.120396 0.3048)
			(stroke
				(width 0.1)
				(type default)
			)
			(layer "B.Fab")
		)
		(fp_line
			(start -0.120396 0.3048)
			(end -0.120396 0.2794)
			(stroke
				(width 0.1)
				(type default)
			)
			(layer "B.Fab")
		)
		(fp_line
			(start 0.12065 0.3048)
			(end 0.67945 0.3048)
			(stroke
				(width 0.1)
				(type default)
			)
			(layer "B.Fab")
		)
		(fp_line
			(start 0.67945 0.3048)
			(end 0.67945 -0.305054)
			(stroke
				(width 0.1)
				(type default)
			)
			(layer "B.Fab")
		)
		(fp_line
			(start -0.120396 0.2794)
			(end 0.12065 0.2794)
			(stroke
				(width 0.1)
				(type default)
			)
			(layer "B.Fab")
		)
		(fp_line
			(start 0.12065 0.2794)
			(end 0.12065 0.3048)
			(stroke
				(width 0.1)
				(type default)
			)
			(layer "B.Fab")
		)
		(fp_line
			(start -0.12065 -0.2794)
			(end -0.12065 -0.3048)
			(stroke
				(width 0.1)
				(type default)
			)
			(layer "B.Fab")
		)
		(fp_line
			(start 0.12065 -0.2794)
			(end -0.12065 -0.2794)
			(stroke
				(width 0.1)
				(type default)
			)
			(layer "B.Fab")
		)
		(fp_line
			(start -0.67945 -0.3048)
			(end -0.67945 0.3048)
			(stroke
				(width 0.1)
				(type default)
			)
			(layer "B.Fab")
		)
		(fp_line
			(start -0.12065 -0.3048)
			(end -0.67945 -0.3048)
			(stroke
				(width 0.1)
				(type default)
			)
			(layer "B.Fab")
		)
		(fp_line
			(start 0.12065 -0.305054)
			(end 0.12065 -0.2794)
			(stroke
				(width 0.1)
				(type default)
			)
			(layer "B.Fab")
		)
		(fp_line
			(start 0.67945 -0.305054)
			(end 0.12065 -0.305054)
			(stroke
				(width 0.1)
				(type default)
			)
			(layer "B.Fab")
		)
		(pad "1" smd circle
			(at 0.40005 0 90)
			(size 0 0)
			(layers "B.Cu" "B.Mask" "B.Paste")
			(net "PVPP_HBM_CPU0_MODE")
		)
		(pad "2" smd circle
			(at -0.40005 0 90)
			(size 0 0)
			(layers "B.Cu" "B.Mask" "B.Paste")
			(net "GND")
		)
	)
	(footprint ""
		(layer "B.Cu")
		(at 103.901494 -252.17628 -90)
		(property "Reference" "C327"
			(at 0 0 90)
			(layer "B.SilkS")
			(hide yes)
			(effects
				(font
					(size 1.27 1.27)
				)
				(justify mirror)
			)
		)
		(property "Value" ""
			(at 0 0 90)
			(layer "B.Fab")
			(effects
				(font
					(size 1.27 1.27)
				)
				(justify mirror)
			)
		)
		(duplicate_pad_numbers_are_jumpers no)
		(fp_line
			(start -1.524 0.762)
			(end 1.524 0.762)
			(stroke
				(width 0.1524)
				(type default)
			)
			(layer "B.SilkS")
		)
		(fp_line
			(start 1.524 0.762)
			(end 1.524 -0.762)
			(stroke
				(width 0.1524)
				(type default)
			)
			(layer "B.SilkS")
		)
		(fp_line
			(start -1.524 -0.762)
			(end -1.524 0.762)
			(stroke
				(width 0.1524)
				(type default)
			)
			(layer "B.SilkS")
		)
		(fp_line
			(start 1.524 -0.762)
			(end -1.524 -0.762)
			(stroke
				(width 0.1524)
				(type default)
			)
			(layer "B.SilkS")
		)
		(fp_line
			(start -1.1049 0.724916)
			(end -1.1049 -0.724916)
			(stroke
				(width 0.1)
				(type default)
			)
			(layer "B.Fab")
		)
		(fp_line
			(start 1.1049 0.724916)
			(end -1.1049 0.724916)
			(stroke
				(width 0.1)
				(type default)
			)
			(layer "B.Fab")
		)
		(fp_line
			(start -1.1049 -0.724916)
			(end 1.1049 -0.724916)
			(stroke
				(width 0.1)
				(type default)
			)
			(layer "B.Fab")
		)
		(fp_line
			(start 1.1049 -0.724916)
			(end 1.1049 0.724916)
			(stroke
				(width 0.1)
				(type default)
			)
			(layer "B.Fab")
		)
		(pad "1" smd rect
			(at 0.889 0 270)
			(size 1.016 1.27)
			(layers "B.Cu" "B.Mask" "B.Paste")
			(net "PVCCIN_CPU1")
		)
		(pad "2" smd rect
			(at -0.889 0 270)
			(size 1.016 1.27)
			(layers "B.Cu" "B.Mask" "B.Paste")
			(net "GND")
		)
	)
	(footprint ""
		(layer "B.Cu")
		(at 53.14188 -171.541948 -90)
		(property "Reference" "PR699"
			(at 0 0 90)
			(layer "B.SilkS")
			(hide yes)
			(effects
				(font
					(size 1.27 1.27)
				)
				(justify mirror)
			)
		)
		(property "Value" ""
			(at 0 0 90)
			(layer "B.Fab")
			(effects
				(font
					(size 1.27 1.27)
				)
				(justify mirror)
			)
		)
		(duplicate_pad_numbers_are_jumpers no)
		(fp_line
			(start -0.7874 0.4064)
			(end 0.7874 0.4064)
			(stroke
				(width 0.1524)
				(type default)
			)
			(layer "B.SilkS")
		)
		(fp_line
			(start 0.7874 0.4064)
			(end 0.7874 -0.4064)
			(stroke
				(width 0.1524)
				(type default)
			)
			(layer "B.SilkS")
		)
		(fp_line
			(start -0.7874 -0.4064)
			(end -0.7874 0.4064)
			(stroke
				(width 0.1524)
				(type default)
			)
			(layer "B.SilkS")
		)
		(fp_line
			(start 0.7874 -0.4064)
			(end -0.7874 -0.4064)
			(stroke
				(width 0.1524)
				(type default)
			)
			(layer "B.SilkS")
		)
		(fp_line
			(start -0.67945 0.3048)
			(end -0.120396 0.3048)
			(stroke
				(width 0.1)
				(type default)
			)
			(layer "B.Fab")
		)
		(fp_line
			(start -0.120396 0.3048)
			(end -0.120396 0.2794)
			(stroke
				(width 0.1)
				(type default)
			)
			(layer "B.Fab")
		)
		(fp_line
			(start 0.12065 0.3048)
			(end 0.67945 0.3048)
			(stroke
				(width 0.1)
				(type default)
			)
			(layer "B.Fab")
		)
		(fp_line
			(start 0.67945 0.3048)
			(end 0.67945 -0.305054)
			(stroke
				(width 0.1)
				(type default)
			)
			(layer "B.Fab")
		)
		(fp_line
			(start -0.120396 0.2794)
			(end 0.12065 0.2794)
			(stroke
				(width 0.1)
				(type default)
			)
			(layer "B.Fab")
		)
		(fp_line
			(start 0.12065 0.2794)
			(end 0.12065 0.3048)
			(stroke
				(width 0.1)
				(type default)
			)
			(layer "B.Fab")
		)
		(fp_line
			(start -0.12065 -0.2794)
			(end -0.12065 -0.3048)
			(stroke
				(width 0.1)
				(type default)
			)
			(layer "B.Fab")
		)
		(fp_line
			(start 0.12065 -0.2794)
			(end -0.12065 -0.2794)
			(stroke
				(width 0.1)
				(type default)
			)
			(layer "B.Fab")
		)
		(fp_line
			(start -0.67945 -0.3048)
			(end -0.67945 0.3048)
			(stroke
				(width 0.1)
				(type default)
			)
			(layer "B.Fab")
		)
		(fp_line
			(start -0.12065 -0.3048)
			(end -0.67945 -0.3048)
			(stroke
				(width 0.1)
				(type default)
			)
			(layer "B.Fab")
		)
		(fp_line
			(start 0.12065 -0.305054)
			(end 0.12065 -0.2794)
			(stroke
				(width 0.1)
				(type default)
			)
			(layer "B.Fab")
		)
		(fp_line
			(start 0.67945 -0.305054)
			(end 0.12065 -0.305054)
			(stroke
				(width 0.1)
				(type default)
			)
			(layer "B.Fab")
		)
		(pad "1" smd circle
			(at 0.40005 0 90)
			(size 0 0)
			(layers "B.Cu" "B.Mask" "B.Paste")
			(net "P3V3")
		)
		(pad "2" smd circle
			(at -0.40005 0 90)
			(size 0 0)
			(layers "B.Cu" "B.Mask" "B.Paste")
			(net "PVCCFA_EHV_CPU1_PVCC")
		)
	)
)
